(kicad_pcb
	(version 20260206)
	(generator "pcbnew")
	(generator_version "10.0")
	(general
		(thickness 1.6)
		(legacy_teardrops no)
	)
	(paper "A4")
	(title_block
		(title "03242023_DA0F0TMBIJ0_F0T_Motherboard_J_brd_V01_OCP.brd")
		(comment 1 "Grand Teton / footprints 5187-5192 of 6105")
	)
	(layers
		(0 "F.Cu" signal "TOP")
		(4 "In1.Cu" signal "GND")
		(6 "In2.Cu" signal "IN1")
		(8 "In3.Cu" signal "GND1")
		(10 "In4.Cu" signal "IN2")
		(12 "In5.Cu" signal "GND2")
		(14 "In6.Cu" signal "IN3")
		(16 "In7.Cu" signal "GND3")
		(18 "In8.Cu" signal "VCC")
		(20 "In9.Cu" signal "VCC1")
		(22 "In10.Cu" signal "GND4")
		(24 "In11.Cu" signal "IN4")
		(26 "In12.Cu" signal "GND5")
		(28 "In13.Cu" signal "IN5")
		(30 "In14.Cu" signal "GND6")
		(32 "In15.Cu" signal "IN6")
		(34 "In16.Cu" signal "GND7")
		(2 "B.Cu" signal "BOTTOM")
		(9 "F.Adhes" user "F.Adhesive")
		(11 "B.Adhes" user "B.Adhesive")
		(13 "F.Paste" user "Package Geometry/Pastemask Top")
		(15 "B.Paste" user "Package Geometry/Pastemask Bottom")
		(5 "F.SilkS" user "Ref Des/Silkscreen Top")
		(7 "B.SilkS" user "Ref Des/Silkscreen Bottom")
		(1 "F.Mask" user "Board Geometry/Soldermask Top")
		(3 "B.Mask" user "Board Geometry/Soldermask Bottom")
		(17 "Dwgs.User" user "User.Drawings")
		(19 "Cmts.User" user "User.Comments")
		(21 "Eco1.User" user "User.Eco1")
		(23 "Eco2.User" user "User.Eco2")
		(25 "Edge.Cuts" user "Board Geometry/Outline")
		(27 "Margin" user)
		(31 "F.CrtYd" user "Package Geometry/Place Bound Top")
		(29 "B.CrtYd" user "Package Geometry/Place Bound Bottom")
		(35 "F.Fab" user "Ref Des/Assembly Top")
		(33 "B.Fab" user "Ref Des/Assembly Bottom")
	)
	(footprint ""
		(layer "B.Cu")
		(at 100.306886 -358.899714 180)
		(property "Reference" "R2552"
			(at 0 0 0)
			(layer "B.SilkS")
			(hide yes)
			(effects
				(font
					(size 1.27 1.27)
				)
				(justify mirror)
			)
		)
		(property "Value" ""
			(at 0 0 0)
			(layer "B.Fab")
			(effects
				(font
					(size 1.27 1.27)
				)
				(justify mirror)
			)
		)
		(duplicate_pad_numbers_are_jumpers no)
		(fp_line
			(start 0.7874 0.4064)
			(end 0.7874 -0.4064)
			(stroke
				(width 0.1524)
				(type default)
			)
			(layer "B.SilkS")
		)
		(fp_line
			(start 0.7874 -0.4064)
			(end -0.7874 -0.4064)
			(stroke
				(width 0.1524)
				(type default)
			)
			(layer "B.SilkS")
		)
		(fp_line
			(start -0.7874 0.4064)
			(end 0.7874 0.4064)
			(stroke
				(width 0.1524)
				(type default)
			)
			(layer "B.SilkS")
		)
		(fp_line
			(start -0.7874 -0.4064)
			(end -0.7874 0.4064)
			(stroke
				(width 0.1524)
				(type default)
			)
			(layer "B.SilkS")
		)
		(fp_line
			(start 0.67945 0.3048)
			(end 0.67945 -0.305054)
			(stroke
				(width 0.1)
				(type default)
			)
			(layer "B.Fab")
		)
		(fp_line
			(start 0.67945 -0.305054)
			(end 0.12065 -0.305054)
			(stroke
				(width 0.1)
				(type default)
			)
			(layer "B.Fab")
		)
		(fp_line
			(start 0.12065 0.3048)
			(end 0.67945 0.3048)
			(stroke
				(width 0.1)
				(type default)
			)
			(layer "B.Fab")
		)
		(fp_line
			(start 0.12065 0.2794)
			(end 0.12065 0.3048)
			(stroke
				(width 0.1)
				(type default)
			)
			(layer "B.Fab")
		)
		(fp_line
			(start 0.12065 -0.2794)
			(end -0.12065 -0.2794)
			(stroke
				(width 0.1)
				(type default)
			)
			(layer "B.Fab")
		)
		(fp_line
			(start 0.12065 -0.305054)
			(end 0.12065 -0.2794)
			(stroke
				(width 0.1)
				(type default)
			)
			(layer "B.Fab")
		)
		(fp_line
			(start -0.120396 0.3048)
			(end -0.120396 0.2794)
			(stroke
				(width 0.1)
				(type default)
			)
			(layer "B.Fab")
		)
		(fp_line
			(start -0.120396 0.2794)
			(end 0.12065 0.2794)
			(stroke
				(width 0.1)
				(type default)
			)
			(layer "B.Fab")
		)
		(fp_line
			(start -0.12065 -0.2794)
			(end -0.12065 -0.3048)
			(stroke
				(width 0.1)
				(type default)
			)
			(layer "B.Fab")
		)
		(fp_line
			(start -0.12065 -0.3048)
			(end -0.67945 -0.3048)
			(stroke
				(width 0.1)
				(type default)
			)
			(layer "B.Fab")
		)
		(fp_line
			(start -0.67945 0.3048)
			(end -0.120396 0.3048)
			(stroke
				(width 0.1)
				(type default)
			)
			(layer "B.Fab")
		)
		(fp_line
			(start -0.67945 -0.3048)
			(end -0.67945 0.3048)
			(stroke
				(width 0.1)
				(type default)
			)
			(layer "B.Fab")
		)
		(pad "1" smd circle
			(at 0.40005 0)
			(size 0 0)
			(layers "B.Cu" "B.Mask" "B.Paste")
			(net "PWRGD_PVCCFA_EHV_FIVRA_CPU1")
		)
		(pad "2" smd circle
			(at -0.40005 0)
			(size 0 0)
			(layers "B.Cu" "B.Mask" "B.Paste")
			(net "PWRGD_PVCCFA_EHV_FIVRA_CPU1_R")
		)
	)
	(footprint ""
		(layer "B.Cu")
		(at 311.84088 -55.336948)
		(property "Reference" "R4104"
			(at 0 0 0)
			(layer "B.SilkS")
			(hide yes)
			(effects
				(font
					(size 1.27 1.27)
				)
				(justify mirror)
			)
		)
		(property "Value" ""
			(at 0 0 0)
			(layer "B.Fab")
			(effects
				(font
					(size 1.27 1.27)
				)
				(justify mirror)
			)
		)
		(duplicate_pad_numbers_are_jumpers no)
		(fp_line
			(start -0.7874 -0.4064)
			(end -0.7874 0.4064)
			(stroke
				(width 0.1524)
				(type default)
			)
			(layer "B.SilkS")
		)
		(fp_line
			(start -0.7874 0.4064)
			(end 0.7874 0.4064)
			(stroke
				(width 0.1524)
				(type default)
			)
			(layer "B.SilkS")
		)
		(fp_line
			(start 0.7874 -0.4064)
			(end -0.7874 -0.4064)
			(stroke
				(width 0.1524)
				(type default)
			)
			(layer "B.SilkS")
		)
		(fp_line
			(start 0.7874 0.4064)
			(end 0.7874 -0.4064)
			(stroke
				(width 0.1524)
				(type default)
			)
			(layer "B.SilkS")
		)
		(fp_line
			(start -0.67945 -0.3048)
			(end -0.67945 0.3048)
			(stroke
				(width 0.1)
				(type default)
			)
			(layer "B.Fab")
		)
		(fp_line
			(start -0.67945 0.3048)
			(end -0.120396 0.3048)
			(stroke
				(width 0.1)
				(type default)
			)
			(layer "B.Fab")
		)
		(fp_line
			(start -0.12065 -0.3048)
			(end -0.67945 -0.3048)
			(stroke
				(width 0.1)
				(type default)
			)
			(layer "B.Fab")
		)
		(fp_line
			(start -0.12065 -0.2794)
			(end -0.12065 -0.3048)
			(stroke
				(width 0.1)
				(type default)
			)
			(layer "B.Fab")
		)
		(fp_line
			(start -0.120396 0.2794)
			(end 0.12065 0.2794)
			(stroke
				(width 0.1)
				(type default)
			)
			(layer "B.Fab")
		)
		(fp_line
			(start -0.120396 0.3048)
			(end -0.120396 0.2794)
			(stroke
				(width 0.1)
				(type default)
			)
			(layer "B.Fab")
		)
		(fp_line
			(start 0.12065 -0.305054)
			(end 0.12065 -0.2794)
			(stroke
				(width 0.1)
				(type default)
			)
			(layer "B.Fab")
		)
		(fp_line
			(start 0.12065 -0.2794)
			(end -0.12065 -0.2794)
			(stroke
				(width 0.1)
				(type default)
			)
			(layer "B.Fab")
		)
		(fp_line
			(start 0.12065 0.2794)
			(end 0.12065 0.3048)
			(stroke
				(width 0.1)
				(type default)
			)
			(layer "B.Fab")
		)
		(fp_line
			(start 0.12065 0.3048)
			(end 0.67945 0.3048)
			(stroke
				(width 0.1)
				(type default)
			)
			(layer "B.Fab")
		)
		(fp_line
			(start 0.67945 -0.305054)
			(end 0.12065 -0.305054)
			(stroke
				(width 0.1)
				(type default)
			)
			(layer "B.Fab")
		)
		(fp_line
			(start 0.67945 0.3048)
			(end 0.67945 -0.305054)
			(stroke
				(width 0.1)
				(type default)
			)
			(layer "B.Fab")
		)
		(pad "1" smd circle
			(at 0.40005 0 180)
			(size 0 0)
			(layers "B.Cu" "B.Mask" "B.Paste")
			(net "PD_GPP_M_16")
		)
		(pad "2" smd circle
			(at -0.40005 0 180)
			(size 0 0)
			(layers "B.Cu" "B.Mask" "B.Paste")
			(net "GND")
		)
	)
	(footprint ""
		(layer "B.Cu")
		(at 160.952942 -318.705992 -90)
		(property "Reference" "R78"
			(at 0 0 90)
			(layer "B.SilkS")
			(hide yes)
			(effects
				(font
					(size 1.27 1.27)
				)
				(justify mirror)
			)
		)
		(property "Value" ""
			(at 0 0 90)
			(layer "B.Fab")
			(effects
				(font
					(size 1.27 1.27)
				)
				(justify mirror)
			)
		)
		(duplicate_pad_numbers_are_jumpers no)
		(fp_line
			(start -0.7874 0.4064)
			(end 0.7874 0.4064)
			(stroke
				(width 0.1524)
				(type default)
			)
			(layer "B.SilkS")
		)
		(fp_line
			(start 0.7874 0.4064)
			(end 0.7874 -0.4064)
			(stroke
				(width 0.1524)
				(type default)
			)
			(layer "B.SilkS")
		)
		(fp_line
			(start -0.7874 -0.4064)
			(end -0.7874 0.4064)
			(stroke
				(width 0.1524)
				(type default)
			)
			(layer "B.SilkS")
		)
		(fp_line
			(start 0.7874 -0.4064)
			(end -0.7874 -0.4064)
			(stroke
				(width 0.1524)
				(type default)
			)
			(layer "B.SilkS")
		)
		(fp_line
			(start -0.67945 0.3048)
			(end -0.120396 0.3048)
			(stroke
				(width 0.1)
				(type default)
			)
			(layer "B.Fab")
		)
		(fp_line
			(start -0.120396 0.3048)
			(end -0.120396 0.2794)
			(stroke
				(width 0.1)
				(type default)
			)
			(layer "B.Fab")
		)
		(fp_line
			(start 0.12065 0.3048)
			(end 0.67945 0.3048)
			(stroke
				(width 0.1)
				(type default)
			)
			(layer "B.Fab")
		)
		(fp_line
			(start 0.67945 0.3048)
			(end 0.67945 -0.305054)
			(stroke
				(width 0.1)
				(type default)
			)
			(layer "B.Fab")
		)
		(fp_line
			(start -0.120396 0.2794)
			(end 0.12065 0.2794)
			(stroke
				(width 0.1)
				(type default)
			)
			(layer "B.Fab")
		)
		(fp_line
			(start 0.12065 0.2794)
			(end 0.12065 0.3048)
			(stroke
				(width 0.1)
				(type default)
			)
			(layer "B.Fab")
		)
		(fp_line
			(start -0.12065 -0.2794)
			(end -0.12065 -0.3048)
			(stroke
				(width 0.1)
				(type default)
			)
			(layer "B.Fab")
		)
		(fp_line
			(start 0.12065 -0.2794)
			(end -0.12065 -0.2794)
			(stroke
				(width 0.1)
				(type default)
			)
			(layer "B.Fab")
		)
		(fp_line
			(start -0.67945 -0.3048)
			(end -0.67945 0.3048)
			(stroke
				(width 0.1)
				(type default)
			)
			(layer "B.Fab")
		)
		(fp_line
			(start -0.12065 -0.3048)
			(end -0.67945 -0.3048)
			(stroke
				(width 0.1)
				(type default)
			)
			(layer "B.Fab")
		)
		(fp_line
			(start 0.12065 -0.305054)
			(end 0.12065 -0.2794)
			(stroke
				(width 0.1)
				(type default)
			)
			(layer "B.Fab")
		)
		(fp_line
			(start 0.67945 -0.305054)
			(end 0.12065 -0.305054)
			(stroke
				(width 0.1)
				(type default)
			)
			(layer "B.Fab")
		)
		(pad "1" smd circle
			(at 0.40005 0 90)
			(size 0 0)
			(layers "B.Cu" "B.Mask" "B.Paste")
			(net "PD_CHE_CPU1_DIMM2_SAA")
		)
		(pad "2" smd circle
			(at -0.40005 0 90)
			(size 0 0)
			(layers "B.Cu" "B.Mask" "B.Paste")
			(net "GND")
		)
	)
	(footprint ""
		(layer "B.Cu")
		(at 342.037416 -37.574728 -90)
		(property "Reference" "R71"
			(at 0 0 90)
			(layer "B.SilkS")
			(hide yes)
			(effects
				(font
					(size 1.27 1.27)
				)
				(justify mirror)
			)
		)
		(property "Value" ""
			(at 0 0 90)
			(layer "B.Fab")
			(effects
				(font
					(size 1.27 1.27)
				)
				(justify mirror)
			)
		)
		(duplicate_pad_numbers_are_jumpers no)
		(fp_line
			(start -0.7874 0.4064)
			(end 0.7874 0.4064)
			(stroke
				(width 0.1524)
				(type default)
			)
			(layer "B.SilkS")
		)
		(fp_line
			(start 0.7874 0.4064)
			(end 0.7874 -0.4064)
			(stroke
				(width 0.1524)
				(type default)
			)
			(layer "B.SilkS")
		)
		(fp_line
			(start -0.7874 -0.4064)
			(end -0.7874 0.4064)
			(stroke
				(width 0.1524)
				(type default)
			)
			(layer "B.SilkS")
		)
		(fp_line
			(start 0.7874 -0.4064)
			(end -0.7874 -0.4064)
			(stroke
				(width 0.1524)
				(type default)
			)
			(layer "B.SilkS")
		)
		(fp_line
			(start -0.67945 0.3048)
			(end -0.120396 0.3048)
			(stroke
				(width 0.1)
				(type default)
			)
			(layer "B.Fab")
		)
		(fp_line
			(start -0.120396 0.3048)
			(end -0.120396 0.2794)
			(stroke
				(width 0.1)
				(type default)
			)
			(layer "B.Fab")
		)
		(fp_line
			(start 0.12065 0.3048)
			(end 0.67945 0.3048)
			(stroke
				(width 0.1)
				(type default)
			)
			(layer "B.Fab")
		)
		(fp_line
			(start 0.67945 0.3048)
			(end 0.67945 -0.305054)
			(stroke
				(width 0.1)
				(type default)
			)
			(layer "B.Fab")
		)
		(fp_line
			(start -0.120396 0.2794)
			(end 0.12065 0.2794)
			(stroke
				(width 0.1)
				(type default)
			)
			(layer "B.Fab")
		)
		(fp_line
			(start 0.12065 0.2794)
			(end 0.12065 0.3048)
			(stroke
				(width 0.1)
				(type default)
			)
			(layer "B.Fab")
		)
		(fp_line
			(start -0.12065 -0.2794)
			(end -0.12065 -0.3048)
			(stroke
				(width 0.1)
				(type default)
			)
			(layer "B.Fab")
		)
		(fp_line
			(start 0.12065 -0.2794)
			(end -0.12065 -0.2794)
			(stroke
				(width 0.1)
				(type default)
			)
			(layer "B.Fab")
		)
		(fp_line
			(start -0.67945 -0.3048)
			(end -0.67945 0.3048)
			(stroke
				(width 0.1)
				(type default)
			)
			(layer "B.Fab")
		)
		(fp_line
			(start -0.12065 -0.3048)
			(end -0.67945 -0.3048)
			(stroke
				(width 0.1)
				(type default)
			)
			(layer "B.Fab")
		)
		(fp_line
			(start 0.12065 -0.305054)
			(end 0.12065 -0.2794)
			(stroke
				(width 0.1)
				(type default)
			)
			(layer "B.Fab")
		)
		(fp_line
			(start 0.67945 -0.305054)
			(end 0.12065 -0.305054)
			(stroke
				(width 0.1)
				(type default)
			)
			(layer "B.Fab")
		)
		(pad "1" smd circle
			(at 0.40005 0 90)
			(size 0 0)
			(layers "B.Cu" "B.Mask" "B.Paste")
			(net "P3V3_AUX")
		)
		(pad "2" smd circle
			(at -0.40005 0 90)
			(size 0 0)
			(layers "B.Cu" "B.Mask" "B.Paste")
			(net "FM_ME_BT_DONE")
		)
	)
	(footprint ""
		(layer "B.Cu")
		(at 295.130474 -354.163376 -90)
		(property "Reference" "PC616_P0_2"
			(at 0 0 90)
			(layer "B.SilkS")
			(hide yes)
			(effects
				(font
					(size 1.27 1.27)
				)
				(justify mirror)
			)
		)
		(property "Value" ""
			(at 0 0 90)
			(layer "B.Fab")
			(effects
				(font
					(size 1.27 1.27)
				)
				(justify mirror)
			)
		)
		(duplicate_pad_numbers_are_jumpers no)
		(fp_line
			(start -1.524 0.762)
			(end 1.524 0.762)
			(stroke
				(width 0.1524)
				(type default)
			)
			(layer "B.SilkS")
		)
		(fp_line
			(start 1.524 0.762)
			(end 1.524 -0.762)
			(stroke
				(width 0.1524)
				(type default)
			)
			(layer "B.SilkS")
		)
		(fp_line
			(start -1.524 -0.762)
			(end -1.524 0.762)
			(stroke
				(width 0.1524)
				(type default)
			)
			(layer "B.SilkS")
		)
		(fp_line
			(start 1.524 -0.762)
			(end -1.524 -0.762)
			(stroke
				(width 0.1524)
				(type default)
			)
			(layer "B.SilkS")
		)
		(fp_line
			(start -1.1049 0.724916)
			(end -1.1049 -0.724916)
			(stroke
				(width 0.1)
				(type default)
			)
			(layer "B.Fab")
		)
		(fp_line
			(start 1.1049 0.724916)
			(end -1.1049 0.724916)
			(stroke
				(width 0.1)
				(type default)
			)
			(layer "B.Fab")
		)
		(fp_line
			(start -1.1049 -0.724916)
			(end 1.1049 -0.724916)
			(stroke
				(width 0.1)
				(type default)
			)
			(layer "B.Fab")
		)
		(fp_line
			(start 1.1049 -0.724916)
			(end 1.1049 0.724916)
			(stroke
				(width 0.1)
				(type default)
			)
			(layer "B.Fab")
		)
		(pad "1" smd rect
			(at 0.889 0 270)
			(size 1.016 1.27)
			(layers "B.Cu" "B.Mask" "B.Paste")
			(net "PVCCFA_EHV_FIVRA_CPU0")
		)
		(pad "2" smd rect
			(at -0.889 0 270)
			(size 1.016 1.27)
			(layers "B.Cu" "B.Mask" "B.Paste")
			(net "GND")
		)
	)
	(footprint ""
		(layer "B.Cu")
		(at 116.84 -86.705948 180)
		(property "Reference" "R4023"
			(at 0 0 0)
			(layer "B.SilkS")
			(hide yes)
			(effects
				(font
					(size 1.27 1.27)
				)
				(justify mirror)
			)
		)
		(property "Value" ""
			(at 0 0 0)
			(layer "B.Fab")
			(effects
				(font
					(size 1.27 1.27)
				)
				(justify mirror)
			)
		)
		(duplicate_pad_numbers_are_jumpers no)
		(fp_line
			(start 0.7874 0.4064)
			(end 0.7874 -0.4064)
			(stroke
				(width 0.1524)
				(type default)
			)
			(layer "B.SilkS")
		)
		(fp_line
			(start 0.7874 -0.4064)
			(end -0.7874 -0.4064)
			(stroke
				(width 0.1524)
				(type default)
			)
			(layer "B.SilkS")
		)
		(fp_line
			(start -0.7874 0.4064)
			(end 0.7874 0.4064)
			(stroke
				(width 0.1524)
				(type default)
			)
			(layer "B.SilkS")
		)
		(fp_line
			(start -0.7874 -0.4064)
			(end -0.7874 0.4064)
			(stroke
				(width 0.1524)
				(type default)
			)
			(layer "B.SilkS")
		)
		(fp_line
			(start 0.67945 0.3048)
			(end 0.67945 -0.305054)
			(stroke
				(width 0.1)
				(type default)
			)
			(layer "B.Fab")
		)
		(fp_line
			(start 0.67945 -0.305054)
			(end 0.12065 -0.305054)
			(stroke
				(width 0.1)
				(type default)
			)
			(layer "B.Fab")
		)
		(fp_line
			(start 0.12065 0.3048)
			(end 0.67945 0.3048)
			(stroke
				(width 0.1)
				(type default)
			)
			(layer "B.Fab")
		)
		(fp_line
			(start 0.12065 0.2794)
			(end 0.12065 0.3048)
			(stroke
				(width 0.1)
				(type default)
			)
			(layer "B.Fab")
		)
		(fp_line
			(start 0.12065 -0.2794)
			(end -0.12065 -0.2794)
			(stroke
				(width 0.1)
				(type default)
			)
			(layer "B.Fab")
		)
		(fp_line
			(start 0.12065 -0.305054)
			(end 0.12065 -0.2794)
			(stroke
				(width 0.1)
				(type default)
			)
			(layer "B.Fab")
		)
		(fp_line
			(start -0.120396 0.3048)
			(end -0.120396 0.2794)
			(stroke
				(width 0.1)
				(type default)
			)
			(layer "B.Fab")
		)
		(fp_line
			(start -0.120396 0.2794)
			(end 0.12065 0.2794)
			(stroke
				(width 0.1)
				(type default)
			)
			(layer "B.Fab")
		)
		(fp_line
			(start -0.12065 -0.2794)
			(end -0.12065 -0.3048)
			(stroke
				(width 0.1)
				(type default)
			)
			(layer "B.Fab")
		)
		(fp_line
			(start -0.12065 -0.3048)
			(end -0.67945 -0.3048)
			(stroke
				(width 0.1)
				(type default)
			)
			(layer "B.Fab")
		)
		(fp_line
			(start -0.67945 0.3048)
			(end -0.120396 0.3048)
			(stroke
				(width 0.1)
				(type default)
			)
			(layer "B.Fab")
		)
		(fp_line
			(start -0.67945 -0.3048)
			(end -0.67945 0.3048)
			(stroke
				(width 0.1)
				(type default)
			)
			(layer "B.Fab")
		)
		(pad "1" smd circle
			(at 0.40005 0)
			(size 0 0)
			(layers "B.Cu" "B.Mask" "B.Paste")
			(net "H_CPU_CATERR_LVC2_R1_N")
		)
		(pad "2" smd circle
			(at -0.40005 0)
			(size 0 0)
			(layers "B.Cu" "B.Mask" "B.Paste")
			(net "H_CPU_CATERR_LVC2_R2_N")
		)
	)
)
